(kicad_pcb
	(version 20260206)
	(generator "pcbnew")
	(generator_version "10.0")
	(general
		(thickness 1.6)
		(legacy_teardrops no)
	)
	(paper "A4")
	(title_block
		(title "v2-pdb — ms_pdb_v2.brd")
		(comment 1 "Open CloudServer (Microsoft) / footprints 93-94 of 348")
	)
	(layers
		(0 "F.Cu" signal "TOP")
		(4 "In1.Cu" signal "GND")
		(6 "In2.Cu" signal "IN1")
		(8 "In3.Cu" signal "VCC")
		(10 "In4.Cu" signal "VCC1")
		(12 "In5.Cu" signal "IN2")
		(14 "In6.Cu" signal "GND1")
		(2 "B.Cu" signal "BOTTOM")
		(9 "F.Adhes" user "F.Adhesive")
		(11 "B.Adhes" user "B.Adhesive")
		(13 "F.Paste" user "Package Geometry/Pastemask Top")
		(15 "B.Paste" user "Package Geometry/Pastemask Bottom")
		(5 "F.SilkS" user "Ref Des/Silkscreen Top")
		(7 "B.SilkS" user "Ref Des/Silkscreen Bottom")
		(1 "F.Mask" user "Board Geometry/Soldermask Top")
		(3 "B.Mask" user "Board Geometry/Soldermask Bottom")
		(17 "Dwgs.User" user "User.Drawings")
		(19 "Cmts.User" user "User.Comments")
		(21 "Eco1.User" user "User.Eco1")
		(23 "Eco2.User" user "User.Eco2")
		(25 "Edge.Cuts" user "Board Geometry/Outline")
		(27 "Margin" user)
		(31 "F.CrtYd" user "Package Geometry/Place Bound Top")
		(29 "B.CrtYd" user "Package Geometry/Place Bound Bottom")
		(35 "F.Fab" user "Ref Des/Assembly Top")
		(33 "B.Fab" user "Ref Des/Assembly Bottom")
	)
	(footprint ""
		(layer "F.Cu")
		(at 27.33421 -197.033896 -90)
		(property "Reference" "R97"
			(at -1.141222 0.065278 90)
			(unlocked yes)
			(layer "F.SilkS")
			(effects
				(font
					(size 0.7874 0.5842)
					(thickness 0.1524)
				)
				(justify left)
			)
		)
		(property "Value" ""
			(at 0 0 270)
			(layer "F.Fab")
			(effects
				(font
					(size 1.27 1.27)
				)
			)
		)
		(duplicate_pad_numbers_are_jumpers no)
		(fp_line
			(start -0.7874 0.4064)
			(end -0.7874 -0.4064)
			(stroke
				(width 0.1524)
				(type default)
			)
			(layer "F.SilkS")
		)
		(fp_line
			(start 0.7874 0.4064)
			(end -0.7874 0.4064)
			(stroke
				(width 0.1524)
				(type default)
			)
			(layer "F.SilkS")
		)
		(fp_line
			(start -0.7874 -0.4064)
			(end 0.7874 -0.4064)
			(stroke
				(width 0.1524)
				(type default)
			)
			(layer "F.SilkS")
		)
		(fp_line
			(start 0.7874 -0.4064)
			(end 0.7874 0.4064)
			(stroke
				(width 0.1524)
				(type default)
			)
			(layer "F.SilkS")
		)
		(fp_poly
			(pts
				(xy -0.508 0.2794) (xy -0.508 0.2286) (xy -0.635 0.2286) (xy -0.635 -0.254) (xy -0.5334 -0.254)
				(xy -0.5334 -0.2794) (xy 0.5334 -0.2794) (xy 0.5334 -0.254) (xy 0.635 -0.254) (xy 0.635 0.254) (xy 0.5334 0.254)
				(xy 0.5334 0.2794)
			)
			(stroke
				(width 0)
				(type default)
			)
			(fill no)
			(layer "F.CrtYd")
		)
		(pad "1" smd rect
			(at 0.40005 0 270)
			(size 0.4572 0.508)
			(layers "F.Cu" "F.Mask" "F.Paste")
			(net "PSU3_REMOTE_N")
		)
		(pad "2" smd rect
			(at -0.40005 0 270)
			(size 0.4572 0.508)
			(layers "F.Cu" "F.Mask" "F.Paste")
			(net "PSU3_REMOTE_R_N")
		)
	)
	(footprint ""
		(layer "F.Cu")
		(at 30.45968 -260.130036)
		(property "Reference" "J3"
			(at -4.153662 5.745988 0)
			(unlocked yes)
			(layer "F.SilkS")
			(effects
				(font
					(size 0.7874 0.5842)
					(thickness 0.1524)
				)
				(justify left)
			)
		)
		(property "Value" ""
			(at 0 0 0)
			(layer "F.Fab")
			(effects
				(font
					(size 1.27 1.27)
				)
			)
		)
		(duplicate_pad_numbers_are_jumpers no)
		(fp_line
			(start -2.135124 -4.560062)
			(end -2.135124 83.300062)
			(stroke
				(width 0.1524)
				(type default)
			)
			(layer "F.SilkS")
		)
		(fp_line
			(start -2.135124 83.300062)
			(end 7.215124 83.300062)
			(stroke
				(width 0.1524)
				(type default)
			)
			(layer "F.SilkS")
		)
		(fp_line
			(start 7.215124 -4.560062)
			(end -2.135124 -4.560062)
			(stroke
				(width 0.1524)
				(type default)
			)
			(layer "F.SilkS")
		)
		(fp_line
			(start 7.215124 83.300062)
			(end 7.215124 -4.560062)
			(stroke
				(width 0.1524)
				(type default)
			)
			(layer "F.SilkS")
		)
		(fp_poly
			(pts
				(xy -2.758694 -0.014732) (xy -5.458714 -0.714756) (xy -5.458714 0.685292)
			)
			(stroke
				(width 0)
				(type default)
			)
			(fill yes)
			(layer "F.SilkS")
		)
		(fp_poly
			(pts
				(xy -2.28219 -0.127) (xy -4.98221 -0.827024) (xy -4.98221 0.573024)
			)
			(stroke
				(width 0)
				(type default)
			)
			(fill yes)
			(layer "B.SilkS")
		)
		(fp_poly
			(pts
				(xy -0.8636 -0.8636) (xy -0.8636 79.6036) (xy -0.8636 79.629) (xy 5.9436 79.629) (xy 5.9436 79.6036)
				(xy 5.9436 -0.8636) (xy 5.9436 -0.889) (xy -0.8636 -0.889)
			)
			(stroke
				(width 0)
				(type default)
			)
			(fill no)
			(layer "B.CrtYd")
		)
		(fp_rect
			(start -2.135124 -4.560062)
			(end 7.21487 83.300062)
			(stroke
				(width 0)
				(type default)
			)
			(fill no)
			(layer "F.CrtYd")
		)
		(fp_line
			(start -2.135124 -4.560062)
			(end 7.215124 -4.560062)
			(stroke
				(width 0.1)
				(type default)
			)
			(layer "F.Fab")
		)
		(fp_line
			(start -2.135124 83.300062)
			(end -2.135124 -4.560062)
			(stroke
				(width 0.1)
				(type default)
			)
			(layer "F.Fab")
		)
		(fp_line
			(start 7.215124 -4.560062)
			(end 7.215124 83.300062)
			(stroke
				(width 0.1)
				(type default)
			)
			(layer "F.Fab")
		)
		(fp_line
			(start 7.215124 83.300062)
			(end -2.135124 83.300062)
			(stroke
				(width 0.1)
				(type default)
			)
			(layer "F.Fab")
		)
		(fp_text user "32"
			(at -3.66268 79.554324 0)
			(unlocked yes)
			(layer "F.SilkS")
			(effects
				(font
					(size 0.7874 0.5842)
					(thickness 0.1524)
				)
				(justify left)
			)
		)
		(fp_text user "1"
			(at -3.093974 -0.810768 0)
			(unlocked yes)
			(layer "F.SilkS")
			(effects
				(font
					(size 0.7874 0.5842)
					(thickness 0.1524)
				)
				(justify left)
			)
		)
		(fp_text user "64"
			(at 7.495794 -0.366014 0)
			(unlocked yes)
			(layer "F.SilkS")
			(effects
				(font
					(size 0.7874 0.5842)
					(thickness 0.1524)
				)
				(justify left)
			)
		)
		(fp_text user "33"
			(at 7.680706 82.813906 0)
			(unlocked yes)
			(layer "F.SilkS")
			(effects
				(font
					(size 0.7874 0.5842)
					(thickness 0.1524)
				)
				(justify left)
			)
		)
		(fp_text user "1"
			(at -1.689608 -0.958596 0)
			(unlocked yes)
			(layer "B.SilkS")
			(effects
				(font
					(size 0.7874 0.5842)
					(thickness 0.1524)
				)
				(justify left mirror)
			)
		)
		(fp_text user "32"
			(at -0.73152 79.809086 0)
			(unlocked yes)
			(layer "B.SilkS")
			(effects
				(font
					(size 0.7874 0.5842)
					(thickness 0.1524)
				)
				(justify left mirror)
			)
		)
		(fp_text user "64"
			(at 5.89153 -1.71323 0)
			(unlocked yes)
			(layer "B.SilkS")
			(effects
				(font
					(size 0.7874 0.5842)
					(thickness 0.1524)
				)
				(justify left mirror)
			)
		)
		(fp_text user "33"
			(at 6.095238 82.893154 0)
			(unlocked yes)
			(layer "B.SilkS")
			(effects
				(font
					(size 0.7874 0.5842)
					(thickness 0.1524)
				)
				(justify left mirror)
			)
		)
		(pad "1" thru_hole rect
			(at 0 0 270)
			(size 1.6256 1.6256)
			(drill 1.1176)
			(layers "*.Cu" "*.Mask")
			(remove_unused_layers no)
			(net "P12V")
			(clearance 0)
			(padstack
				(mode front_inner_back)
				(layer "Inner"
					(shape circle)
					(size 1.6256 1.6256)
					(clearance 0)
				)
				(layer "B.Cu"
					(shape rect)
					(size 1.6256 1.6256)
					(clearance 0)
				)
			)
		)
		(pad "2" thru_hole circle
			(at 0 2.54 270)
			(size 1.6256 1.6256)
			(drill 1.1176)
			(layers "*.Cu" "*.Mask")
			(remove_unused_layers no)
			(net "P12V")
			(clearance 0)
		)
		(pad "3" thru_hole circle
			(at 0 5.08 270)
			(size 1.6256 1.6256)
			(drill 1.1176)
			(layers "*.Cu" "*.Mask")
			(remove_unused_layers no)
			(net "P12V")
			(clearance 0)
		)
		(pad "4" thru_hole circle
			(at 0 7.62 270)
			(size 1.6256 1.6256)
			(drill 1.1176)
			(layers "*.Cu" "*.Mask")
			(remove_unused_layers no)
			(net "P12V")
			(clearance 0)
		)
		(pad "5" thru_hole circle
			(at 0 10.16 270)
			(size 1.6256 1.6256)
			(drill 1.1176)
			(layers "*.Cu" "*.Mask")
			(remove_unused_layers no)
			(net "P12V")
			(clearance 0)
		)
		(pad "6" thru_hole circle
			(at 0 12.7 270)
			(size 1.6256 1.6256)
			(drill 1.1176)
			(layers "*.Cu" "*.Mask")
			(remove_unused_layers no)
			(net "P12V")
			(clearance 0)
		)
		(pad "7" thru_hole circle
			(at 0 15.24 270)
			(size 1.6256 1.6256)
			(drill 1.1176)
			(layers "*.Cu" "*.Mask")
			(remove_unused_layers no)
			(net "P12V")
			(clearance 0)
		)
		(pad "8" thru_hole circle
			(at 0 17.78 270)
			(size 1.6256 1.6256)
			(drill 1.1176)
			(layers "*.Cu" "*.Mask")
			(remove_unused_layers no)
			(net "P12V")
			(clearance 0)
		)
		(pad "9" thru_hole circle
			(at 0 20.32 270)
			(size 1.6256 1.6256)
			(drill 1.1176)
			(layers "*.Cu" "*.Mask")
			(remove_unused_layers no)
			(net "P12V")
			(clearance 0)
		)
		(pad "10" thru_hole circle
			(at 0 22.86 270)
			(size 1.6256 1.6256)
			(drill 1.1176)
			(layers "*.Cu" "*.Mask")
			(remove_unused_layers no)
			(net "P12V")
			(clearance 0)
		)
		(pad "11" thru_hole circle
			(at 0 25.4 270)
			(size 1.6256 1.6256)
			(drill 1.1176)
			(layers "*.Cu" "*.Mask")
			(remove_unused_layers no)
			(net "P12V")
			(clearance 0)
		)
		(pad "12" thru_hole circle
			(at 0 27.94 270)
			(size 1.6256 1.6256)
			(drill 1.1176)
			(layers "*.Cu" "*.Mask")
			(remove_unused_layers no)
			(net "P12V")
			(clearance 0)
		)
		(pad "13" thru_hole circle
			(at 0 30.48 270)
			(size 1.6256 1.6256)
			(drill 1.1176)
			(layers "*.Cu" "*.Mask")
			(remove_unused_layers no)
			(net "GND")
			(clearance 0)
		)
		(pad "14" thru_hole circle
			(at 0 33.02 270)
			(size 1.6256 1.6256)
			(drill 1.1176)
			(layers "*.Cu" "*.Mask")
			(remove_unused_layers no)
			(net "GND")
			(clearance 0)
		)
		(pad "15" thru_hole circle
			(at 0 35.56 270)
			(size 1.6256 1.6256)
			(drill 1.1176)
			(layers "*.Cu" "*.Mask")
			(remove_unused_layers no)
			(net "GND")
			(clearance 0)
		)
		(pad "16" thru_hole circle
			(at 0 38.1 270)
			(size 1.6256 1.6256)
			(drill 1.1176)
			(layers "*.Cu" "*.Mask")
			(remove_unused_layers no)
			(net "GND")
			(clearance 0)
		)
		(pad "17" thru_hole circle
			(at 0 40.64 270)
			(size 1.6256 1.6256)
			(drill 1.1176)
			(layers "*.Cu" "*.Mask")
			(remove_unused_layers no)
			(net "GND")
			(clearance 0)
		)
		(pad "18" thru_hole circle
			(at 0 43.18 270)
			(size 1.6256 1.6256)
			(drill 1.1176)
			(layers "*.Cu" "*.Mask")
			(remove_unused_layers no)
			(net "GND")
			(clearance 0)
		)
		(pad "19" thru_hole circle
			(at 0 45.72 270)
			(size 1.6256 1.6256)
			(drill 1.1176)
			(layers "*.Cu" "*.Mask")
			(remove_unused_layers no)
			(net "GND")
			(clearance 0)
		)
		(pad "20" thru_hole circle
			(at 0 48.26 270)
			(size 1.6256 1.6256)
			(drill 1.1176)
			(layers "*.Cu" "*.Mask")
			(remove_unused_layers no)
			(net "GND")
			(clearance 0)
		)
		(pad "21" thru_hole circle
			(at 0 50.8 270)
			(size 1.6256 1.6256)
			(drill 1.1176)
			(layers "*.Cu" "*.Mask")
			(remove_unused_layers no)
			(net "GND")
			(clearance 0)
		)
		(pad "22" thru_hole circle
			(at 0 53.34 270)
			(size 1.6256 1.6256)
			(drill 1.1176)
			(layers "*.Cu" "*.Mask")
			(remove_unused_layers no)
			(net "GND")
			(clearance 0)
		)
		(pad "23" thru_hole circle
			(at 0 55.88 270)
			(size 1.6256 1.6256)
			(drill 1.1176)
			(layers "*.Cu" "*.Mask")
			(remove_unused_layers no)
			(net "GND")
			(clearance 0)
		)
		(pad "24" thru_hole circle
			(at 0 58.42 270)
			(size 1.6256 1.6256)
			(drill 1.1176)
			(layers "*.Cu" "*.Mask")
			(remove_unused_layers no)
			(net "GND")
			(clearance 0)
		)
		(pad "25" thru_hole circle
			(at 0 60.96 270)
			(size 1.6256 1.6256)
			(drill 1.1176)
			(layers "*.Cu" "*.Mask")
			(remove_unused_layers no)
			(net "PHLOSS")
			(clearance 0)
		)
		(pad "26" thru_hole circle
			(at 0 63.5 270)
			(size 1.6256 1.6256)
			(drill 1.1176)
			(layers "*.Cu" "*.Mask")
			(remove_unused_layers no)
			(net "PSU3_REMOTE_N")
			(clearance 0)
		)
		(pad "27" thru_hole circle
			(at 0 66.04 270)
			(size 1.6256 1.6256)
			(drill 1.1176)
			(layers "*.Cu" "*.Mask")
			(remove_unused_layers no)
			(net "PSU3_AC_OK")
			(clearance 0)
		)
		(pad "28" thru_hole circle
			(at 0 68.58 270)
			(size 1.6256 1.6256)
			(drill 1.1176)
			(layers "*.Cu" "*.Mask")
			(remove_unused_layers no)
			(net "PSU3_CSAHRE")
			(clearance 0)
		)
		(pad "29" thru_hole circle
			(at 0 71.12 270)
			(size 1.6256 1.6256)
			(drill 1.1176)
			(layers "*.Cu" "*.Mask")
			(remove_unused_layers no)
			(net "PSU3_PS_ON_N")
			(clearance 0)
		)
		(pad "30" thru_hole circle
			(at 0 73.66 270)
			(size 1.6256 1.6256)
			(drill 1.1176)
			(layers "*.Cu" "*.Mask")
			(remove_unused_layers no)
			(net "PSU3_PS_KILL")
			(clearance 0)
		)
		(pad "31" thru_hole circle
			(at 0 76.2 270)
			(size 1.6256 1.6256)
			(drill 1.1176)
			(layers "*.Cu" "*.Mask")
			(remove_unused_layers no)
			(net "PSU3_RESET")
			(clearance 0)
		)
		(pad "32" thru_hole circle
			(at 0 78.74 270)
			(size 1.6256 1.6256)
			(drill 1.1176)
			(layers "*.Cu" "*.Mask")
			(remove_unused_layers no)
			(net "PSU_ALERT_N")
			(clearance 0)
		)
		(pad "33" thru_hole circle
			(at 5.08 78.74 270)
			(size 1.6256 1.6256)
			(drill 1.1176)
			(layers "*.Cu" "*.Mask")
			(remove_unused_layers no)
			(net "I2C_PSU2_SDA")
			(clearance 0)
		)
		(pad "34" thru_hole circle
			(at 5.08 76.2 270)
			(size 1.6256 1.6256)
			(drill 1.1176)
			(layers "*.Cu" "*.Mask")
			(remove_unused_layers no)
			(net "Net_428")
			(clearance 0)
		)
		(pad "35" thru_hole circle
			(at 5.08 73.66 270)
			(size 1.6256 1.6256)
			(drill 1.1176)
			(layers "*.Cu" "*.Mask")
			(remove_unused_layers no)
			(net "I2C_PSU2_SCL")
			(clearance 0)
		)
		(pad "36" thru_hole circle
			(at 5.08 71.12 270)
			(size 1.6256 1.6256)
			(drill 1.1176)
			(layers "*.Cu" "*.Mask")
			(remove_unused_layers no)
			(net "PSU3_RETURN")
			(clearance 0)
		)
		(pad "37" thru_hole circle
			(at 5.08 68.58 270)
			(size 1.6256 1.6256)
			(drill 1.1176)
			(layers "*.Cu" "*.Mask")
			(remove_unused_layers no)
			(net "PSU3_DC_OK")
			(clearance 0)
		)
		(pad "38" thru_hole circle
			(at 5.08 66.04 270)
			(size 1.6256 1.6256)
			(drill 1.1176)
			(layers "*.Cu" "*.Mask")
			(remove_unused_layers no)
			(net "PSU3_AD0")
			(clearance 0)
		)
		(pad "39" thru_hole circle
			(at 5.08 63.5 270)
			(size 1.6256 1.6256)
			(drill 1.1176)
			(layers "*.Cu" "*.Mask")
			(remove_unused_layers no)
			(net "P12V_STBY")
			(clearance 0)
		)
		(pad "40" thru_hole circle
			(at 5.08 60.96 270)
			(size 1.6256 1.6256)
			(drill 1.1176)
			(layers "*.Cu" "*.Mask")
			(remove_unused_layers no)
			(net "PSU3_REMOTE_P")
			(clearance 0)
		)
		(pad "41" thru_hole circle
			(at 5.08 58.42 270)
			(size 1.6256 1.6256)
			(drill 1.1176)
			(layers "*.Cu" "*.Mask")
			(remove_unused_layers no)
			(net "GND")
			(clearance 0)
		)
		(pad "42" thru_hole circle
			(at 5.08 55.88 270)
			(size 1.6256 1.6256)
			(drill 1.1176)
			(layers "*.Cu" "*.Mask")
			(remove_unused_layers no)
			(net "GND")
			(clearance 0)
		)
		(pad "43" thru_hole circle
			(at 5.08 53.34 270)
			(size 1.6256 1.6256)
			(drill 1.1176)
			(layers "*.Cu" "*.Mask")
			(remove_unused_layers no)
			(net "GND")
			(clearance 0)
		)
		(pad "44" thru_hole circle
			(at 5.08 50.8 270)
			(size 1.6256 1.6256)
			(drill 1.1176)
			(layers "*.Cu" "*.Mask")
			(remove_unused_layers no)
			(net "GND")
			(clearance 0)
		)
		(pad "45" thru_hole circle
			(at 5.08 48.26 270)
			(size 1.6256 1.6256)
			(drill 1.1176)
			(layers "*.Cu" "*.Mask")
			(remove_unused_layers no)
			(net "GND")
			(clearance 0)
		)
		(pad "46" thru_hole circle
			(at 5.08 45.72 270)
			(size 1.6256 1.6256)
			(drill 1.1176)
			(layers "*.Cu" "*.Mask")
			(remove_unused_layers no)
			(net "GND")
			(clearance 0)
		)
		(pad "47" thru_hole circle
			(at 5.08 43.18 270)
			(size 1.6256 1.6256)
			(drill 1.1176)
			(layers "*.Cu" "*.Mask")
			(remove_unused_layers no)
			(net "GND")
			(clearance 0)
		)
		(pad "48" thru_hole circle
			(at 5.08 40.64 270)
			(size 1.6256 1.6256)
			(drill 1.1176)
			(layers "*.Cu" "*.Mask")
			(remove_unused_layers no)
			(net "GND")
			(clearance 0)
		)
		(pad "49" thru_hole circle
			(at 5.08 38.1 270)
			(size 1.6256 1.6256)
			(drill 1.1176)
			(layers "*.Cu" "*.Mask")
			(remove_unused_layers no)
			(net "GND")
			(clearance 0)
		)
		(pad "50" thru_hole circle
			(at 5.08 35.56 270)
			(size 1.6256 1.6256)
			(drill 1.1176)
			(layers "*.Cu" "*.Mask")
			(remove_unused_layers no)
			(net "GND")
			(clearance 0)
		)
		(pad "51" thru_hole circle
			(at 5.08 33.02 270)
			(size 1.6256 1.6256)
			(drill 1.1176)
			(layers "*.Cu" "*.Mask")
			(remove_unused_layers no)
			(net "GND")
			(clearance 0)
		)
		(pad "52" thru_hole circle
			(at 5.08 30.48 270)
			(size 1.6256 1.6256)
			(drill 1.1176)
			(layers "*.Cu" "*.Mask")
			(remove_unused_layers no)
			(net "GND")
			(clearance 0)
		)
		(pad "53" thru_hole circle
			(at 5.08 27.94 270)
			(size 1.6256 1.6256)
			(drill 1.1176)
			(layers "*.Cu" "*.Mask")
			(remove_unused_layers no)
			(net "P12V")
			(clearance 0)
		)
		(pad "54" thru_hole circle
			(at 5.08 25.4 270)
			(size 1.6256 1.6256)
			(drill 1.1176)
			(layers "*.Cu" "*.Mask")
			(remove_unused_layers no)
			(net "P12V")
			(clearance 0)
		)
		(pad "55" thru_hole circle
			(at 5.08 22.86 270)
			(size 1.6256 1.6256)
			(drill 1.1176)
			(layers "*.Cu" "*.Mask")
			(remove_unused_layers no)
			(net "P12V")
			(clearance 0)
		)
		(pad "56" thru_hole circle
			(at 5.08 20.32 270)
			(size 1.6256 1.6256)
			(drill 1.1176)
			(layers "*.Cu" "*.Mask")
			(remove_unused_layers no)
			(net "P12V")
			(clearance 0)
		)
		(pad "57" thru_hole circle
			(at 5.08 17.78 270)
			(size 1.6256 1.6256)
			(drill 1.1176)
			(layers "*.Cu" "*.Mask")
			(remove_unused_layers no)
			(net "P12V")
			(clearance 0)
		)
		(pad "58" thru_hole circle
			(at 5.08 15.24 270)
			(size 1.6256 1.6256)
			(drill 1.1176)
			(layers "*.Cu" "*.Mask")
			(remove_unused_layers no)
			(net "P12V")
			(clearance 0)
		)
		(pad "59" thru_hole circle
			(at 5.08 12.7 270)
			(size 1.6256 1.6256)
			(drill 1.1176)
			(layers "*.Cu" "*.Mask")
			(remove_unused_layers no)
			(net "P12V")
			(clearance 0)
		)
		(pad "60" thru_hole circle
			(at 5.08 10.16 270)
			(size 1.6256 1.6256)
			(drill 1.1176)
			(layers "*.Cu" "*.Mask")
			(remove_unused_layers no)
			(net "P12V")
			(clearance 0)
		)
		(pad "61" thru_hole circle
			(at 5.08 7.62 270)
			(size 1.6256 1.6256)
			(drill 1.1176)
			(layers "*.Cu" "*.Mask")
			(remove_unused_layers no)
			(net "P12V")
			(clearance 0)
		)
		(pad "62" thru_hole circle
			(at 5.08 5.08 270)
			(size 1.6256 1.6256)
			(drill 1.1176)
			(layers "*.Cu" "*.Mask")
			(remove_unused_layers no)
			(net "P12V")
			(clearance 0)
		)
		(pad "63" thru_hole circle
			(at 5.08 2.54 270)
			(size 1.6256 1.6256)
			(drill 1.1176)
			(layers "*.Cu" "*.Mask")
			(remove_unused_layers no)
			(net "P12V")
			(clearance 0)
		)
		(pad "64" thru_hole circle
			(at 5.08 0 270)
			(size 1.6256 1.6256)
			(drill 1.1176)
			(layers "*.Cu" "*.Mask")
			(remove_unused_layers no)
			(net "P12V")
			(clearance 0)
		)
	)
)
